(kicad_pcb
	(version 20260206)
	(generator "pcbnew")
	(generator_version "10.0")
	(general
		(thickness 1.6)
		(legacy_teardrops no)
	)
	(paper "A4")
	(title_block
		(title "pdpb — Lightning_PDPB_BRD.brd")
		(comment 1 "Lightning (Wiwynn / Facebook NVMe JBOF) / footprints 1095-1095 of 1140")
	)
	(layers
		(0 "F.Cu" signal "TOP")
		(4 "In1.Cu" signal "L2GND")
		(6 "In2.Cu" signal "L3")
		(8 "In3.Cu" signal "L4VCC")
		(10 "In4.Cu" signal "L5VCC")
		(12 "In5.Cu" signal "L6")
		(14 "In6.Cu" signal "L7GND")
		(2 "B.Cu" signal "BOTTOM")
		(9 "F.Adhes" user "F.Adhesive")
		(11 "B.Adhes" user "B.Adhesive")
		(13 "F.Paste" user "Package Geometry/Pastemask Top")
		(15 "B.Paste" user "Package Geometry/Pastemask Bottom")
		(5 "F.SilkS" user "Ref Des/Silkscreen Top")
		(7 "B.SilkS" user "Ref Des/Silkscreen Bottom")
		(1 "F.Mask" user "Board Geometry/Soldermask Top")
		(3 "B.Mask" user "Board Geometry/Soldermask Bottom")
		(17 "Dwgs.User" user "User.Drawings")
		(19 "Cmts.User" user "User.Comments")
		(21 "Eco1.User" user "User.Eco1")
		(23 "Eco2.User" user "User.Eco2")
		(25 "Edge.Cuts" user "Board Geometry/Outline")
		(27 "Margin" user)
		(31 "F.CrtYd" user "Package Geometry/Place Bound Top")
		(29 "B.CrtYd" user "Package Geometry/Place Bound Bottom")
		(35 "F.Fab" user "Ref Des/Assembly Top")
		(33 "B.Fab" user "Ref Des/Assembly Bottom")
	)
	(footprint ""
		(layer "F.Cu")
		(at 83.185 -152.654 -90)
		(property "Reference" "SR1151"
			(at 0 0 270)
			(layer "F.SilkS")
			(hide yes)
			(effects
				(font
					(size 1.27 1.27)
				)
			)
		)
		(property "Value" "4K7R2F-GP"
			(at 0.064008 -3.993896 270)
			(unlocked yes)
			(layer "F.Fab")
			(hide yes)
			(effects
				(font
					(size 1.016 1.016)
					(thickness 0.1524)
				)
			)
		)
		(property "Device Type" "R402H16"
			(at 0.064008 -5.517896 270)
			(unlocked yes)
			(layer "F.Fab")
			(hide yes)
			(effects
				(font
					(size 1.016 1.016)
					(thickness 0.1524)
				)
			)
		)
		(duplicate_pad_numbers_are_jumpers no)
		(fp_line
			(start -0.508 -0.9398)
			(end -0.508 0.9398)
			(stroke
				(width 0.1524)
				(type default)
			)
			(layer "F.SilkS")
		)
		(fp_line
			(start 0.508 -0.9398)
			(end -0.508 -0.9398)
			(stroke
				(width 0.1524)
				(type default)
			)
			(layer "F.SilkS")
		)
		(fp_rect
			(start -0.508 0.9398)
			(end 0.508 -0.9398)
			(stroke
				(width 0)
				(type default)
			)
			(fill no)
			(layer "F.CrtYd")
		)
		(fp_rect
			(start -0.508 0.9398)
			(end 0.508 -0.9398)
			(stroke
				(width 0)
				(type default)
			)
			(fill no)
			(layer "F.Fab")
		)
		(pad "1" smd custom
			(at 0 -0.4445 270)
			(size 0.1397 0.1397)
			(layers "F.Cu" "F.Mask" "F.Paste")
			(net "P3V3")
			(options
				(clearance outline)
				(anchor circle)
			)
			(primitives
				(gr_poly
					(pts
						(arc
							(start -0.1778 -0.2794)
							(mid -0.249642 -0.249642)
							(end -0.2794 -0.1778)
						)
						(arc
							(start -0.2794 0.1778)
							(mid -0.249642 0.249642)
							(end -0.1778 0.2794)
						)
						(arc
							(start 0.1778 0.2794)
							(mid 0.249642 0.249642)
							(end 0.2794 0.1778)
						)
						(arc
							(start 0.2794 -0.1778)
							(mid 0.249642 -0.249642)
							(end 0.1778 -0.2794)
						)
					)
					(width 0)
					(fill yes)
				)
			)
		)
		(pad "2" smd custom
			(at 0 0.4445 270)
			(size 0.1397 0.1397)
			(layers "F.Cu" "F.Mask" "F.Paste")
			(net "I2C_SW_EU16_ADDRESS_A1")
			(options
				(clearance outline)
				(anchor circle)
			)
			(primitives
				(gr_poly
					(pts
						(arc
							(start -0.1778 -0.2794)
							(mid -0.249642 -0.249642)
							(end -0.2794 -0.1778)
						)
						(arc
							(start -0.2794 0.1778)
							(mid -0.249642 0.249642)
							(end -0.1778 0.2794)
						)
						(arc
							(start 0.1778 0.2794)
							(mid 0.249642 0.249642)
							(end 0.2794 0.1778)
						)
						(arc
							(start 0.2794 -0.1778)
							(mid 0.249642 -0.249642)
							(end 0.1778 -0.2794)
						)
					)
					(width 0)
					(fill yes)
				)
			)
		)
	)
)
